(kicad_pcb
	(version 20260206)
	(generator "pcbnew")
	(generator_version "10.0")
	(general
		(thickness 1.6)
		(legacy_teardrops no)
	)
	(paper "A4")
	(title_block
		(title "03242023_DA0F0TMBIJ0_F0T_Motherboard_J_brd_V01_OCP.brd")
		(comment 1 "Grand Teton / footprint 1368 of 6105 (J13), pads 225-291 of 291")
	)
	(layers
		(0 "F.Cu" signal "TOP")
		(4 "In1.Cu" signal "GND")
		(6 "In2.Cu" signal "IN1")
		(8 "In3.Cu" signal "GND1")
		(10 "In4.Cu" signal "IN2")
		(12 "In5.Cu" signal "GND2")
		(14 "In6.Cu" signal "IN3")
		(16 "In7.Cu" signal "GND3")
		(18 "In8.Cu" signal "VCC")
		(20 "In9.Cu" signal "VCC1")
		(22 "In10.Cu" signal "GND4")
		(24 "In11.Cu" signal "IN4")
		(26 "In12.Cu" signal "GND5")
		(28 "In13.Cu" signal "IN5")
		(30 "In14.Cu" signal "GND6")
		(32 "In15.Cu" signal "IN6")
		(34 "In16.Cu" signal "GND7")
		(2 "B.Cu" signal "BOTTOM")
		(9 "F.Adhes" user "F.Adhesive")
		(11 "B.Adhes" user "B.Adhesive")
		(13 "F.Paste" user "Package Geometry/Pastemask Top")
		(15 "B.Paste" user "Package Geometry/Pastemask Bottom")
		(5 "F.SilkS" user "Ref Des/Silkscreen Top")
		(7 "B.SilkS" user "Ref Des/Silkscreen Bottom")
		(1 "F.Mask" user "Board Geometry/Soldermask Top")
		(3 "B.Mask" user "Board Geometry/Soldermask Bottom")
		(17 "Dwgs.User" user "User.Drawings")
		(19 "Cmts.User" user "User.Comments")
		(21 "Eco1.User" user "User.Eco1")
		(23 "Eco2.User" user "User.Eco2")
		(25 "Edge.Cuts" user "Board Geometry/Outline")
		(27 "Margin" user)
		(31 "F.CrtYd" user "Package Geometry/Place Bound Top")
		(29 "B.CrtYd" user "Package Geometry/Place Bound Bottom")
		(35 "F.Fab" user "Ref Des/Assembly Top")
		(33 "B.Fab" user "Ref Des/Assembly Bottom")
	)
	(footprint ""
		(layer "F.Cu")
		(at 446.522348 -258.091686)
		(property "Reference" "J13"
			(at -3.683 -81.702148 0)
			(unlocked yes)
			(layer "F.SilkS")
			(effects
				(font
					(size 0.7874 0.5842)
					(thickness 0.1524)
				)
				(justify left)
			)
		)
		(property "Value" ""
			(at 0 0 0)
			(layer "F.Fab")
			(effects
				(font
					(size 1.27 1.27)
				)
			)
		)
		(duplicate_pad_numbers_are_jumpers no)
		(pad "225" smd rect
			(at 2.050034 9.774936 270)
			(size 0.519938 1.4986)
			(layers "F.Cu" "F.Mask" "F.Paste")
			(net "M_G_CPU0_SB_CA<5>")
		)
		(pad "226" smd rect
			(at 2.050034 10.625074 270)
			(size 0.519938 1.4986)
			(layers "F.Cu" "F.Mask" "F.Paste")
			(net "GND")
		)
		(pad "227" smd rect
			(at 2.050034 11.474958 270)
			(size 0.519938 1.4986)
			(layers "F.Cu" "F.Mask" "F.Paste")
			(net "M_G_CPU0_SB_PAR")
		)
		(pad "228" smd rect
			(at 2.050034 12.325096 270)
			(size 0.519938 1.4986)
			(layers "F.Cu" "F.Mask" "F.Paste")
			(net "GND")
		)
		(pad "229" smd rect
			(at 2.050034 13.17498 270)
			(size 0.519938 1.4986)
			(layers "F.Cu" "F.Mask" "F.Paste")
			(net "M_G_CPU0_SB_CS_N<1>")
		)
		(pad "230" smd rect
			(at 2.050034 14.025118 270)
			(size 0.519938 1.4986)
			(layers "F.Cu" "F.Mask" "F.Paste")
			(net "GND")
		)
		(pad "231" smd rect
			(at 2.050034 14.875002 270)
			(size 0.519938 1.4986)
			(layers "F.Cu" "F.Mask" "F.Paste")
			(net "TP_CHG_CPU0_DIMM1_FRU_5")
		)
		(pad "232" smd rect
			(at 2.050034 15.724886 270)
			(size 0.519938 1.4986)
			(layers "F.Cu" "F.Mask" "F.Paste")
			(net "TP_CHG_CPU0_DIMM1_FRU_6")
		)
		(pad "233" smd rect
			(at 2.050034 16.575024 270)
			(size 0.519938 1.4986)
			(layers "F.Cu" "F.Mask" "F.Paste")
			(net "GND")
		)
		(pad "234" smd rect
			(at 2.050034 17.424908 270)
			(size 0.519938 1.4986)
			(layers "F.Cu" "F.Mask" "F.Paste")
			(net "M_G_CPU0_SB_CB<6>")
		)
		(pad "235" smd rect
			(at 2.050034 18.275046 270)
			(size 0.519938 1.4986)
			(layers "F.Cu" "F.Mask" "F.Paste")
			(net "GND")
		)
		(pad "236" smd rect
			(at 2.050034 19.12493 270)
			(size 0.519938 1.4986)
			(layers "F.Cu" "F.Mask" "F.Paste")
			(net "M_G_CPU0_SB_CB<7>")
		)
		(pad "237" smd rect
			(at 2.050034 19.975068 270)
			(size 0.519938 1.4986)
			(layers "F.Cu" "F.Mask" "F.Paste")
			(net "GND")
		)
		(pad "238" smd rect
			(at 2.050034 20.824952 270)
			(size 0.519938 1.4986)
			(layers "F.Cu" "F.Mask" "F.Paste")
			(net "M_G_CPU0_SB_DQS_DN<4>")
		)
		(pad "239" smd rect
			(at 2.050034 21.67509 270)
			(size 0.519938 1.4986)
			(layers "F.Cu" "F.Mask" "F.Paste")
			(net "M_G_CPU0_SB_DQS_DP<4>")
		)
		(pad "240" smd rect
			(at 2.050034 22.524974 270)
			(size 0.519938 1.4986)
			(layers "F.Cu" "F.Mask" "F.Paste")
			(net "GND")
		)
		(pad "241" smd rect
			(at 2.050034 23.375112 270)
			(size 0.519938 1.4986)
			(layers "F.Cu" "F.Mask" "F.Paste")
			(net "M_G_CPU0_SB_CB<2>")
		)
		(pad "242" smd rect
			(at 2.050034 24.224996 270)
			(size 0.519938 1.4986)
			(layers "F.Cu" "F.Mask" "F.Paste")
			(net "GND")
		)
		(pad "243" smd rect
			(at 2.050034 25.07488 270)
			(size 0.519938 1.4986)
			(layers "F.Cu" "F.Mask" "F.Paste")
			(net "M_G_CPU0_SB_CB<3>")
		)
		(pad "244" smd rect
			(at 2.050034 25.925018 270)
			(size 0.519938 1.4986)
			(layers "F.Cu" "F.Mask" "F.Paste")
			(net "GND")
		)
		(pad "245" smd rect
			(at 2.050034 26.774902 270)
			(size 0.519938 1.4986)
			(layers "F.Cu" "F.Mask" "F.Paste")
			(net "M_G_CPU0_SB_DQ<2>")
		)
		(pad "246" smd rect
			(at 2.050034 27.62504 270)
			(size 0.519938 1.4986)
			(layers "F.Cu" "F.Mask" "F.Paste")
			(net "GND")
		)
		(pad "247" smd rect
			(at 2.050034 28.474924 270)
			(size 0.519938 1.4986)
			(layers "F.Cu" "F.Mask" "F.Paste")
			(net "M_G_CPU0_SB_DQ<3>")
		)
		(pad "248" smd rect
			(at 2.050034 29.325062 270)
			(size 0.519938 1.4986)
			(layers "F.Cu" "F.Mask" "F.Paste")
			(net "GND")
		)
		(pad "249" smd rect
			(at 2.050034 30.174946 270)
			(size 0.519938 1.4986)
			(layers "F.Cu" "F.Mask" "F.Paste")
			(net "M_G_CPU0_SB_DQS_DN<5>")
		)
		(pad "250" smd rect
			(at 2.050034 31.025084 270)
			(size 0.519938 1.4986)
			(layers "F.Cu" "F.Mask" "F.Paste")
			(net "M_G_CPU0_SB_DQS_DP<5>")
		)
		(pad "251" smd rect
			(at 2.050034 31.874968 270)
			(size 0.519938 1.4986)
			(layers "F.Cu" "F.Mask" "F.Paste")
			(net "GND")
		)
		(pad "252" smd rect
			(at 2.050034 32.725106 270)
			(size 0.519938 1.4986)
			(layers "F.Cu" "F.Mask" "F.Paste")
			(net "M_G_CPU0_SB_DQ<6>")
		)
		(pad "253" smd rect
			(at 2.050034 33.57499 270)
			(size 0.519938 1.4986)
			(layers "F.Cu" "F.Mask" "F.Paste")
			(net "GND")
		)
		(pad "254" smd rect
			(at 2.050034 34.425128 270)
			(size 0.519938 1.4986)
			(layers "F.Cu" "F.Mask" "F.Paste")
			(net "M_G_CPU0_SB_DQ<7>")
		)
		(pad "255" smd rect
			(at 2.050034 35.275012 270)
			(size 0.519938 1.4986)
			(layers "F.Cu" "F.Mask" "F.Paste")
			(net "GND")
		)
		(pad "256" smd rect
			(at 2.050034 36.124896 270)
			(size 0.519938 1.4986)
			(layers "F.Cu" "F.Mask" "F.Paste")
			(net "M_G_CPU0_SB_DQ<10>")
		)
		(pad "257" smd rect
			(at 2.050034 36.975034 270)
			(size 0.519938 1.4986)
			(layers "F.Cu" "F.Mask" "F.Paste")
			(net "GND")
		)
		(pad "258" smd rect
			(at 2.050034 37.824918 270)
			(size 0.519938 1.4986)
			(layers "F.Cu" "F.Mask" "F.Paste")
			(net "M_G_CPU0_SB_DQ<11>")
		)
		(pad "259" smd rect
			(at 2.050034 38.675056 270)
			(size 0.519938 1.4986)
			(layers "F.Cu" "F.Mask" "F.Paste")
			(net "GND")
		)
		(pad "260" smd rect
			(at 2.050034 39.52494 270)
			(size 0.519938 1.4986)
			(layers "F.Cu" "F.Mask" "F.Paste")
			(net "M_G_CPU0_SB_DQS_DN<6>")
		)
		(pad "261" smd rect
			(at 2.050034 40.375078 270)
			(size 0.519938 1.4986)
			(layers "F.Cu" "F.Mask" "F.Paste")
			(net "M_G_CPU0_SB_DQS_DP<6>")
		)
		(pad "262" smd rect
			(at 2.050034 41.224962 270)
			(size 0.519938 1.4986)
			(layers "F.Cu" "F.Mask" "F.Paste")
			(net "GND")
		)
		(pad "263" smd rect
			(at 2.050034 42.0751 270)
			(size 0.519938 1.4986)
			(layers "F.Cu" "F.Mask" "F.Paste")
			(net "M_G_CPU0_SB_DQ<14>")
		)
		(pad "264" smd rect
			(at 2.050034 42.924984 270)
			(size 0.519938 1.4986)
			(layers "F.Cu" "F.Mask" "F.Paste")
			(net "GND")
		)
		(pad "265" smd rect
			(at 2.050034 43.775122 270)
			(size 0.519938 1.4986)
			(layers "F.Cu" "F.Mask" "F.Paste")
			(net "M_G_CPU0_SB_DQ<15>")
		)
		(pad "266" smd rect
			(at 2.050034 44.625006 270)
			(size 0.519938 1.4986)
			(layers "F.Cu" "F.Mask" "F.Paste")
			(net "GND")
		)
		(pad "267" smd rect
			(at 2.050034 45.47489 270)
			(size 0.519938 1.4986)
			(layers "F.Cu" "F.Mask" "F.Paste")
			(net "M_G_CPU0_SB_DQ<18>")
		)
		(pad "268" smd rect
			(at 2.050034 46.325028 270)
			(size 0.519938 1.4986)
			(layers "F.Cu" "F.Mask" "F.Paste")
			(net "GND")
		)
		(pad "269" smd rect
			(at 2.050034 47.174912 270)
			(size 0.519938 1.4986)
			(layers "F.Cu" "F.Mask" "F.Paste")
			(net "M_G_CPU0_SB_DQ<19>")
		)
		(pad "270" smd rect
			(at 2.050034 48.02505 270)
			(size 0.519938 1.4986)
			(layers "F.Cu" "F.Mask" "F.Paste")
			(net "GND")
		)
		(pad "271" smd rect
			(at 2.050034 48.874934 270)
			(size 0.519938 1.4986)
			(layers "F.Cu" "F.Mask" "F.Paste")
			(net "M_G_CPU0_SB_DQS_DN<7>")
		)
		(pad "272" smd rect
			(at 2.050034 49.725072 270)
			(size 0.519938 1.4986)
			(layers "F.Cu" "F.Mask" "F.Paste")
			(net "M_G_CPU0_SB_DQS_DP<7>")
		)
		(pad "273" smd rect
			(at 2.050034 50.574956 270)
			(size 0.519938 1.4986)
			(layers "F.Cu" "F.Mask" "F.Paste")
			(net "GND")
		)
		(pad "274" smd rect
			(at 2.050034 51.425094 270)
			(size 0.519938 1.4986)
			(layers "F.Cu" "F.Mask" "F.Paste")
			(net "M_G_CPU0_SB_DQ<22>")
		)
		(pad "275" smd rect
			(at 2.050034 52.274978 270)
			(size 0.519938 1.4986)
			(layers "F.Cu" "F.Mask" "F.Paste")
			(net "GND")
		)
		(pad "276" smd rect
			(at 2.050034 53.125116 270)
			(size 0.519938 1.4986)
			(layers "F.Cu" "F.Mask" "F.Paste")
			(net "M_G_CPU0_SB_DQ<23>")
		)
		(pad "277" smd rect
			(at 2.050034 53.975 270)
			(size 0.519938 1.4986)
			(layers "F.Cu" "F.Mask" "F.Paste")
			(net "GND")
		)
		(pad "278" smd rect
			(at 2.050034 54.824884 270)
			(size 0.519938 1.4986)
			(layers "F.Cu" "F.Mask" "F.Paste")
			(net "M_G_CPU0_SB_DQ<26>")
		)
		(pad "279" smd rect
			(at 2.050034 55.675022 270)
			(size 0.519938 1.4986)
			(layers "F.Cu" "F.Mask" "F.Paste")
			(net "GND")
		)
		(pad "280" smd rect
			(at 2.050034 56.524906 270)
			(size 0.519938 1.4986)
			(layers "F.Cu" "F.Mask" "F.Paste")
			(net "M_G_CPU0_SB_DQ<27>")
		)
		(pad "281" smd rect
			(at 2.050034 57.375044 270)
			(size 0.519938 1.4986)
			(layers "F.Cu" "F.Mask" "F.Paste")
			(net "GND")
		)
		(pad "282" smd rect
			(at 2.050034 58.224928 270)
			(size 0.519938 1.4986)
			(layers "F.Cu" "F.Mask" "F.Paste")
			(net "M_G_CPU0_SB_DQS_DN<8>")
		)
		(pad "283" smd rect
			(at 2.050034 59.075066 270)
			(size 0.519938 1.4986)
			(layers "F.Cu" "F.Mask" "F.Paste")
			(net "M_G_CPU0_SB_DQS_DP<8>")
		)
		(pad "284" smd rect
			(at 2.050034 59.92495 270)
			(size 0.519938 1.4986)
			(layers "F.Cu" "F.Mask" "F.Paste")
			(net "GND")
		)
		(pad "285" smd rect
			(at 2.050034 60.775088 270)
			(size 0.519938 1.4986)
			(layers "F.Cu" "F.Mask" "F.Paste")
			(net "M_G_CPU0_SB_DQ<30>")
		)
		(pad "286" smd rect
			(at 2.050034 61.624972 270)
			(size 0.519938 1.4986)
			(layers "F.Cu" "F.Mask" "F.Paste")
			(net "GND")
		)
		(pad "287" smd rect
			(at 2.050034 62.47511 270)
			(size 0.519938 1.4986)
			(layers "F.Cu" "F.Mask" "F.Paste")
			(net "M_G_CPU0_SB_DQ<31>")
		)
		(pad "288" smd rect
			(at 2.050034 63.324994 270)
			(size 0.519938 1.4986)
			(layers "F.Cu" "F.Mask" "F.Paste")
			(net "GND")
		)
		(pad "G1" thru_hole oval
			(at 0 -68.97497)
			(size 2.8194 1.5748)
			(drill oval 2.4384 1.1938)
			(layers "*.Cu" "*.Mask")
			(remove_unused_layers no)
			(net "GND")
			(clearance 0.127)
			(thermal_gap 0.127)
		)
		(pad "G2" thru_hole oval
			(at 0 3.875024)
			(size 2.8194 1.5748)
			(drill oval 2.4384 1.1938)
			(layers "*.Cu" "*.Mask")
			(remove_unused_layers no)
			(net "GND")
			(clearance 0.127)
			(thermal_gap 0.127)
		)
		(pad "G3" thru_hole oval
			(at 0 68.97497)
			(size 2.8194 1.5748)
			(drill oval 2.4384 1.1938)
			(layers "*.Cu" "*.Mask")
			(remove_unused_layers no)
			(net "GND")
			(clearance 0.127)
			(thermal_gap 0.127)
		)
	)
)
